FILE_TYPE = MULTI_PHYS_TABLE;

PART 'ISL99390FRZTR5935'

{========================================================================================}
:VALUE                | PART_TYPE | MATERIAL | PART_NUMBER    = STANDARD        | LIFECYCLE     | PART_NUMBER   | JEDEC_TYPE    | DESCRIPTION                            | MANUFTR | MANUF_PN             | RD_CMPLS_LVL | CMPLS_LVL | FROM_PJ     | CLASS | DIP_SMD | DATA                         | EE_CHECK_LIST | FP_ECN | PSL | CREATOR | STATUS | MSD  | ESD_CDM | ESD_HBM | ESD_MM | PIN_LENGTH_SHORT_PIN | PIN_LENGTH_LONG_PIN | CREATEDAY  ;
{========================================================================================}
 'ISL99390FRZ-TR5935' | 'SMLF'    | 'IC'     | 'AL099390004'(!) = ''               | ''               | 'AL099390004' |'QFN21_6X5XB'| 'IC CTRL(41P) ISL99390FRZ-TR5935(QFN)' | 'RTT'   | 'ISL99390FRZ-TR5935' | 'EP(V1)'     | ''        | 'S8A-KENNY' | 'IC'  | ''      | 'RTT_ISL99390FRZ-TR5935.pdf' | ''            | ''     | ''  | ''      | ''     | 'NA' | 'NA'    | 'NA'    | 'NA'   | '0 MILS'             | '0 MILS'            | '20200303'
 'ISL99390FRZ-TR5935' | 'SMLF'    | 'EMPTY'  | 'AL099390004'(!) = ''               | ''               | 'AL099390004' |'QFN21_6X5XB'| 'IC CTRL(41P) ISL99390FRZ-TR5935(QFN)' | 'RTT'   | 'ISL99390FRZ-TR5935' | 'EP(V1)'     | ''        | 'S8A-KENNY' | 'IC'  | ''      | 'RTT_ISL99390FRZ-TR5935.pdf' | ''            | ''     | ''  | ''      | ''     | 'NA' | 'NA'    | 'NA'    | 'NA'   | '0 MILS'             | '0 MILS'            | '20200303'

END_PART

END.

